# T6G (Grand Teton) — schematic netlist excerpt (pin names and nets, part order shuffled) for the footprints in the layout excerpt that follows; sources: Cadence DE-HDL packaged netlist, KiCad conversion of 04192023_DAF0TMB3IC0_F0TG_MB_C_brd_V02_OCP.brd

PR526  Q_RES  1.5 1% EMPTY  pkg 0402LF  page 215 : A = SW_PVDDCR_SOC_P1_SW2_RC ; B = GND
C1514  Q_CAP  0.1UF 16V 10% X7R  pkg C0402  page 173 : A = PVDD18_S5_P0 ; B = GND

(kicad_pcb
	(version 20260206)
	(generator "pcbnew")
	(generator_version "10.0")
	(general
		(thickness 1.6)
		(legacy_teardrops no)
	)
	(paper "A4")
	(title_block
		(title "04192023_DAF0TMB3IC0_F0TG_MB_C_brd_V02_OCP.brd")
		(comment 1 "Grand Teton / footprints 2976-2977 of 8354")
	)
	(layers
		(0 "F.Cu" signal "TOP")
		(4 "In1.Cu" signal "GND")
		(6 "In2.Cu" signal "IN1")
		(8 "In3.Cu" signal "GND1")
		(10 "In4.Cu" signal "IN2")
		(12 "In5.Cu" signal "GND2")
		(14 "In6.Cu" signal "IN3")
		(16 "In7.Cu" signal "GND3")
		(18 "In8.Cu" signal "VCC")
		(20 "In9.Cu" signal "VCC1")
		(22 "In10.Cu" signal "GND4")
		(24 "In11.Cu" signal "IN4")
		(26 "In12.Cu" signal "GND5")
		(28 "In13.Cu" signal "IN5")
		(30 "In14.Cu" signal "GND6")
		(32 "In15.Cu" signal "IN6")
		(34 "In16.Cu" signal "GND7")
		(2 "B.Cu" signal "BOTTOM")
		(9 "F.Adhes" user "F.Adhesive")
		(11 "B.Adhes" user "B.Adhesive")
		(13 "F.Paste" user "Package Geometry/Pastemask Top")
		(15 "B.Paste" user "Package Geometry/Pastemask Bottom")
		(5 "F.SilkS" user "Ref Des/Silkscreen Top")
		(7 "B.SilkS" user "Ref Des/Silkscreen Bottom")
		(1 "F.Mask" user "Board Geometry/Soldermask Top")
		(3 "B.Mask" user "Board Geometry/Soldermask Bottom")
		(17 "Dwgs.User" user "User.Drawings")
		(19 "Cmts.User" user "User.Comments")
		(21 "Eco1.User" user "User.Eco1")
		(23 "Eco2.User" user "User.Eco2")
		(25 "Edge.Cuts" user "Board Geometry/Outline")
		(27 "Margin" user)
		(31 "F.CrtYd" user "Package Geometry/Place Bound Top")
		(29 "B.CrtYd" user "Package Geometry/Place Bound Bottom")
		(35 "F.Fab" user "Ref Des/Assembly Top")
		(33 "B.Fab" user "Ref Des/Assembly Bottom")
	)
	(footprint ""
		(layer "F.Cu")
		(at 127.643128 -166.926768 -90)
		(property "Reference" "PR526"
			(at 0 0 270)
			(layer "F.SilkS")
			(hide yes)
			(effects
				(font
					(size 1.27 1.27)
				)
			)
		)
		(property "Value" ""
			(at 0 0 270)
			(layer "F.Fab")
			(effects
				(font
					(size 1.27 1.27)
				)
			)
		)
		(duplicate_pad_numbers_are_jumpers no)
		(fp_line
			(start -0.7874 0.4064)
			(end -0.7874 -0.4064)
			(stroke
				(width 0.1524)
				(type default)
			)
			(layer "F.SilkS")
		)
		(fp_line
			(start 0.7874 0.4064)
			(end -0.7874 0.4064)
			(stroke
				(width 0.1524)
				(type default)
			)
			(layer "F.SilkS")
		)
		(fp_line
			(start -0.7874 -0.4064)
			(end 0.7874 -0.4064)
			(stroke
				(width 0.1524)
				(type default)
			)
			(layer "F.SilkS")
		)
		(fp_line
			(start 0.7874 -0.4064)
			(end 0.7874 0.4064)
			(stroke
				(width 0.1524)
				(type default)
			)
			(layer "F.SilkS")
		)
		(fp_line
			(start -0.67945 0.3048)
			(end -0.67945 -0.305054)
			(stroke
				(width 0.1)
				(type default)
			)
			(layer "F.Fab")
		)
		(fp_line
			(start -0.12065 0.3048)
			(end -0.67945 0.3048)
			(stroke
				(width 0.1)
				(type default)
			)
			(layer "F.Fab")
		)
		(fp_line
			(start 0.120396 0.3048)
			(end 0.120396 0.2794)
			(stroke
				(width 0.1)
				(type default)
			)
			(layer "F.Fab")
		)
		(fp_line
			(start 0.67945 0.3048)
			(end 0.120396 0.3048)
			(stroke
				(width 0.1)
				(type default)
			)
			(layer "F.Fab")
		)
		(fp_line
			(start -0.12065 0.2794)
			(end -0.12065 0.3048)
			(stroke
				(width 0.1)
				(type default)
			)
			(layer "F.Fab")
		)
		(fp_line
			(start 0.120396 0.2794)
			(end -0.12065 0.2794)
			(stroke
				(width 0.1)
				(type default)
			)
			(layer "F.Fab")
		)
		(fp_line
			(start -0.12065 -0.2794)
			(end 0.12065 -0.2794)
			(stroke
				(width 0.1)
				(type default)
			)
			(layer "F.Fab")
		)
		(fp_line
			(start 0.12065 -0.2794)
			(end 0.12065 -0.3048)
			(stroke
				(width 0.1)
				(type default)
			)
			(layer "F.Fab")
		)
		(fp_line
			(start 0.12065 -0.3048)
			(end 0.67945 -0.3048)
			(stroke
				(width 0.1)
				(type default)
			)
			(layer "F.Fab")
		)
		(fp_line
			(start 0.67945 -0.3048)
			(end 0.67945 0.3048)
			(stroke
				(width 0.1)
				(type default)
			)
			(layer "F.Fab")
		)
		(fp_line
			(start -0.67945 -0.305054)
			(end -0.12065 -0.305054)
			(stroke
				(width 0.1)
				(type default)
			)
			(layer "F.Fab")
		)
		(fp_line
			(start -0.12065 -0.305054)
			(end -0.12065 -0.2794)
			(stroke
				(width 0.1)
				(type default)
			)
			(layer "F.Fab")
		)
		(pad "1" smd circle
			(at -0.40005 0 270)
			(size 0 0)
			(layers "F.Cu" "F.Mask" "F.Paste")
			(net "SW_PVDDCR_SOC_P1_SW2_RC")
		)
		(pad "2" smd circle
			(at 0.40005 0 270)
			(size 0 0)
			(layers "F.Cu" "F.Mask" "F.Paste")
			(net "GND")
		)
	)
	(footprint ""
		(layer "F.Cu")
		(at 256.442972 -101.74351 -90)
		(property "Reference" "C1514"
			(at 0 0 270)
			(layer "F.SilkS")
			(hide yes)
			(effects
				(font
					(size 1.27 1.27)
				)
			)
		)
		(property "Value" ""
			(at 0 0 270)
			(layer "F.Fab")
			(effects
				(font
					(size 1.27 1.27)
				)
			)
		)
		(duplicate_pad_numbers_are_jumpers no)
		(fp_line
			(start -0.7874 0.4064)
			(end -0.7874 -0.4064)
			(stroke
				(width 0.1524)
				(type default)
			)
			(layer "F.SilkS")
		)
		(fp_line
			(start 0.7874 0.4064)
			(end -0.7874 0.4064)
			(stroke
				(width 0.1524)
				(type default)
			)
			(layer "F.SilkS")
		)
		(fp_line
			(start -0.7874 -0.4064)
			(end 0.7874 -0.4064)
			(stroke
				(width 0.1524)
				(type default)
			)
			(layer "F.SilkS")
		)
		(fp_line
			(start 0.7874 -0.4064)
			(end 0.7874 0.4064)
			(stroke
				(width 0.1524)
				(type default)
			)
			(layer "F.SilkS")
		)
		(fp_line
			(start -0.67945 0.3048)
			(end -0.67945 -0.305054)
			(stroke
				(width 0.1)
				(type default)
			)
			(layer "F.Fab")
		)
		(fp_line
			(start -0.12065 0.3048)
			(end -0.67945 0.3048)
			(stroke
				(width 0.1)
				(type default)
			)
			(layer "F.Fab")
		)
		(fp_line
			(start 0.120396 0.3048)
			(end 0.120396 0.2794)
			(stroke
				(width 0.1)
				(type default)
			)
			(layer "F.Fab")
		)
		(fp_line
			(start 0.67945 0.3048)
			(end 0.120396 0.3048)
			(stroke
				(width 0.1)
				(type default)
			)
			(layer "F.Fab")
		)
		(fp_line
			(start -0.12065 0.2794)
			(end -0.12065 0.3048)
			(stroke
				(width 0.1)
				(type default)
			)
			(layer "F.Fab")
		)
		(fp_line
			(start 0.120396 0.2794)
			(end -0.12065 0.2794)
			(stroke
				(width 0.1)
				(type default)
			)
			(layer "F.Fab")
		)
		(fp_line
			(start -0.12065 -0.2794)
			(end 0.12065 -0.2794)
			(stroke
				(width 0.1)
				(type default)
			)
			(layer "F.Fab")
		)
		(fp_line
			(start 0.12065 -0.2794)
			(end 0.12065 -0.3048)
			(stroke
				(width 0.1)
				(type default)
			)
			(layer "F.Fab")
		)
		(fp_line
			(start 0.12065 -0.3048)
			(end 0.67945 -0.3048)
			(stroke
				(width 0.1)
				(type default)
			)
			(layer "F.Fab")
		)
		(fp_line
			(start 0.67945 -0.3048)
			(end 0.67945 0.3048)
			(stroke
				(width 0.1)
				(type default)
			)
			(layer "F.Fab")
		)
		(fp_line
			(start -0.67945 -0.305054)
			(end -0.12065 -0.305054)
			(stroke
				(width 0.1)
				(type default)
			)
			(layer "F.Fab")
		)
		(fp_line
			(start -0.12065 -0.305054)
			(end -0.12065 -0.2794)
			(stroke
				(width 0.1)
				(type default)
			)
			(layer "F.Fab")
		)
		(pad "1" smd circle
			(at -0.40005 0 270)
			(size 0 0)
			(layers "F.Cu" "F.Mask" "F.Paste")
			(net "PVDD18_S5_P0")
		)
		(pad "2" smd circle
			(at 0.40005 0 270)
			(size 0 0)
			(layers "F.Cu" "F.Mask" "F.Paste")
			(net "GND")
		)
	)
)
